# BASEBOARD_FAB2 (Tioga Pass) — schematic netlist excerpt (pin names and nets, part order shuffled) for the footprints in the layout excerpt that follows; sources: Cadence DE-HDL packaged netlist, KiCad conversion of Wiwynn_Tioga_Pass_MB.brd

C7G13  CAP  0.22UF 16V 10% X7R  pkg 0402  page 105 : A = P3E_CPU0_PE2_SS_TXN<11> ; B = P3E_CPU0_PE2_SS_C_TXN<11>
R4D71  RES  68.1K 1% EMPTY  pkg 0402  page 203 : A = VR_PVCCIN_CPU0_PH4_OCSET ; B = GND

(kicad_pcb
	(version 20260206)
	(generator "pcbnew")
	(generator_version "10.0")
	(general
		(thickness 1.6)
		(legacy_teardrops no)
	)
	(paper "A4")
	(title_block
		(title "Wiwynn_Tioga_Pass_MB.brd")
		(comment 1 "Tioga Pass / footprints 702-703 of 4770")
	)
	(layers
		(0 "F.Cu" signal "TOP")
		(4 "In1.Cu" signal "L2GND")
		(6 "In2.Cu" signal "L3")
		(8 "In3.Cu" signal "L4GND")
		(10 "In4.Cu" signal "L5")
		(12 "In5.Cu" signal "L6GND")
		(14 "In6.Cu" signal "L7VCC")
		(16 "In7.Cu" signal "L8VCC")
		(18 "In8.Cu" signal "L9GND")
		(20 "In9.Cu" signal "L10")
		(22 "In10.Cu" signal "L11GND")
		(24 "In11.Cu" signal "L12")
		(26 "In12.Cu" signal "L13GND")
		(2 "B.Cu" signal "BOTTOM")
		(9 "F.Adhes" user "F.Adhesive")
		(11 "B.Adhes" user "B.Adhesive")
		(13 "F.Paste" user "Package Geometry/Pastemask Top")
		(15 "B.Paste" user "Package Geometry/Pastemask Bottom")
		(5 "F.SilkS" user "Ref Des/Silkscreen Top")
		(7 "B.SilkS" user "Ref Des/Silkscreen Bottom")
		(1 "F.Mask" user "Board Geometry/Soldermask Top")
		(3 "B.Mask" user "Board Geometry/Soldermask Bottom")
		(17 "Dwgs.User" user "User.Drawings")
		(19 "Cmts.User" user "User.Comments")
		(21 "Eco1.User" user "User.Eco1")
		(23 "Eco2.User" user "User.Eco2")
		(25 "Edge.Cuts" user "Board Geometry/Outline")
		(27 "Margin" user)
		(31 "F.CrtYd" user "Package Geometry/Place Bound Top")
		(29 "B.CrtYd" user "Package Geometry/Place Bound Bottom")
		(35 "F.Fab" user "Ref Des/Assembly Top")
		(33 "B.Fab" user "Ref Des/Assembly Bottom")
	)
	(footprint ""
		(layer "F.Cu")
		(at 193.653918 -80.363568 -90)
		(property "Reference" "R4D71"
			(at 0 0 270)
			(layer "F.SilkS")
			(hide yes)
			(effects
				(font
					(size 1.27 1.27)
				)
			)
		)
		(property "Value" ""
			(at 0 0 270)
			(layer "F.Fab")
			(effects
				(font
					(size 1.27 1.27)
				)
			)
		)
		(duplicate_pad_numbers_are_jumpers no)
		(fp_poly
			(pts
				(xy -0.2794 -0.1016) (xy 0.2794 -0.1016) (xy 0.2794 0.9906) (xy -0.2794 0.9906)
			)
			(stroke
				(width 0)
				(type default)
			)
			(fill no)
			(layer "F.CrtYd")
		)
		(fp_line
			(start -0.2794 0.9906)
			(end 0.2794 0.9906)
			(stroke
				(width 0.1)
				(type default)
			)
			(layer "F.Fab")
		)
		(fp_line
			(start 0.2794 0.9906)
			(end 0.2794 -0.1016)
			(stroke
				(width 0.1)
				(type default)
			)
			(layer "F.Fab")
		)
		(fp_line
			(start -0.2794 -0.1016)
			(end -0.2794 0.9906)
			(stroke
				(width 0.1)
				(type default)
			)
			(layer "F.Fab")
		)
		(fp_line
			(start 0.2794 -0.1016)
			(end -0.2794 -0.1016)
			(stroke
				(width 0.1)
				(type default)
			)
			(layer "F.Fab")
		)
		(pad "1" smd rect
			(at 0 0 270)
			(size 0.508 0.508)
			(layers "F.Cu" "F.Mask" "F.Paste")
			(net "VR_PVCCIN_CPU0_PH4_OCSET")
		)
		(pad "2" smd rect
			(at 0 0.889 270)
			(size 0.508 0.508)
			(layers "F.Cu" "F.Mask" "F.Paste")
			(net "GND")
		)
		(zone
			(layer "F.Cu")
			(hatch none 0.5)
			(connect_pads
				(clearance 0)
			)
			(min_thickness 0.25)
			(keepout
				(tracks not_allowed)
				(vias allowed)
				(pads allowed)
				(copperpour not_allowed)
				(footprints allowed)
			)
			(placement
				(enabled no)
				(sheetname "")
			)
			(fill
				(thermal_gap 0.5)
				(thermal_bridge_width 0.5)
				(island_removal_mode 0)
			)
			(polygon
				(pts
					(xy 193.018918 -80.617568) (xy 193.018918 -80.109568) (xy 193.399918 -80.109568) (xy 193.399918 -80.617568)
				)
			)
		)
		(zone
			(layer "F.Cu")
			(hatch none 0.5)
			(connect_pads
				(clearance 0)
			)
			(min_thickness 0.25)
			(keepout
				(tracks allowed)
				(vias not_allowed)
				(pads allowed)
				(copperpour not_allowed)
				(footprints allowed)
			)
			(placement
				(enabled no)
				(sheetname "")
			)
			(fill
				(thermal_gap 0.5)
				(thermal_bridge_width 0.5)
				(island_removal_mode 0)
			)
			(polygon
				(pts
					(xy 193.399918 -80.617568) (xy 193.399918 -80.109568) (xy 193.018918 -80.109568) (xy 193.018918 -80.617568)
				)
			)
		)
	)
	(footprint ""
		(layer "F.Cu")
		(at 371.877844 -10.916158)
		(property "Reference" "C7G13"
			(at 0 0 0)
			(layer "F.SilkS")
			(hide yes)
			(effects
				(font
					(size 1.27 1.27)
				)
			)
		)
		(property "Value" ""
			(at 0 0 0)
			(layer "F.Fab")
			(effects
				(font
					(size 1.27 1.27)
				)
			)
		)
		(duplicate_pad_numbers_are_jumpers no)
		(fp_rect
			(start -0.3048 0.9906)
			(end 0.3048 -0.1016)
			(stroke
				(width 0)
				(type default)
			)
			(fill no)
			(layer "F.CrtYd")
		)
		(fp_line
			(start -0.3048 -0.1016)
			(end -0.3048 0.9906)
			(stroke
				(width 0.1)
				(type default)
			)
			(layer "F.Fab")
		)
		(fp_line
			(start -0.3048 0.9906)
			(end 0.3048 0.9906)
			(stroke
				(width 0.1)
				(type default)
			)
			(layer "F.Fab")
		)
		(fp_line
			(start 0.3048 -0.1016)
			(end -0.3048 -0.1016)
			(stroke
				(width 0.1)
				(type default)
			)
			(layer "F.Fab")
		)
		(fp_line
			(start 0.3048 0.9906)
			(end 0.3048 -0.1016)
			(stroke
				(width 0.1)
				(type default)
			)
			(layer "F.Fab")
		)
		(pad "1" smd rect
			(at 0 0)
			(size 0.508 0.508)
			(layers "F.Cu" "F.Mask" "F.Paste")
			(net "P3E_CPU0_PE2_SS_TXN<11>")
		)
		(pad "2" smd rect
			(at 0 0.889)
			(size 0.508 0.508)
			(layers "F.Cu" "F.Mask" "F.Paste")
			(net "P3E_CPU0_PE2_SS_C_TXN<11>")
		)
		(zone
			(layer "F.Cu")
			(hatch none 0.5)
			(connect_pads
				(clearance 0)
			)
			(min_thickness 0.25)
			(keepout
				(tracks allowed)
				(vias not_allowed)
				(pads allowed)
				(copperpour not_allowed)
				(footprints allowed)
			)
			(placement
				(enabled no)
				(sheetname "")
			)
			(fill
				(thermal_gap 0.5)
				(thermal_bridge_width 0.5)
				(island_removal_mode 0)
			)
			(polygon
				(pts
					(xy 371.623844 -10.281158) (xy 372.131844 -10.281158) (xy 372.131844 -10.662158) (xy 371.623844 -10.662158)
				)
			)
		)
		(zone
			(layer "F.Cu")
			(hatch none 0.5)
			(connect_pads
				(clearance 0)
			)
			(min_thickness 0.25)
			(keepout
				(tracks not_allowed)
				(vias allowed)
				(pads allowed)
				(copperpour not_allowed)
				(footprints allowed)
			)
			(placement
				(enabled no)
				(sheetname "")
			)
			(fill
				(thermal_gap 0.5)
				(thermal_bridge_width 0.5)
				(island_removal_mode 0)
			)
			(polygon
				(pts
					(xy 371.623844 -10.281158) (xy 372.131844 -10.281158) (xy 372.131844 -10.662158) (xy 371.623844 -10.662158)
				)
			)
		)
	)
)
